(kicad_pcb
	(version 20241229)
	(generator "pcbnew")
	(generator_version "9.0")
	(general
		(thickness 1.6642)
		(legacy_teardrops no)
	)
	(paper "A3")
	(title_block
		(title "PolarFire SoM")
		(date "2025-07-22")
		(rev "1.1.4")
		(company "Antmicro Ltd")
		(comment 1 "www.antmicro.com")
		(comment 9 "footprints 378-381 of 470")
	)
	(layers
		(0 "F.Cu" mixed)
		(4 "In1.Cu" power)
		(6 "In2.Cu" signal)
		(8 "In3.Cu" power)
		(10 "In4.Cu" signal)
		(12 "In5.Cu" power)
		(14 "In6.Cu" power)
		(16 "In7.Cu" signal)
		(18 "In8.Cu" power)
		(20 "In9.Cu" signal)
		(22 "In10.Cu" power)
		(24 "In11.Cu" signal)
		(26 "In12.Cu" signal)
		(2 "B.Cu" mixed)
		(9 "F.Adhes" user "F.Adhesive")
		(11 "B.Adhes" user "B.Adhesive")
		(13 "F.Paste" user)
		(15 "B.Paste" user)
		(5 "F.SilkS" user "F.Silkscreen")
		(7 "B.SilkS" user "B.Silkscreen")
		(1 "F.Mask" user)
		(3 "B.Mask" user)
		(17 "Dwgs.User" user "User.Drawings")
		(19 "Cmts.User" user "User.Comments")
		(21 "Eco1.User" user "User.Eco1")
		(23 "Eco2.User" user "User.Eco2")
		(25 "Edge.Cuts" user)
		(27 "Margin" user)
		(31 "F.CrtYd" user "F.Courtyard")
		(29 "B.CrtYd" user "B.Courtyard")
		(35 "F.Fab" user)
		(33 "B.Fab" user)
	)
	(footprint "antmicro-footprints:C_0402_1005Metric"
		(layer "B.Cu")
		(at 197.04 132.79 90)
		(descr "Capacitor SMD 0402")
		(tags "capacitor SMD 0402")
		(property "Reference" "C28"
			(at 7.79 -9.615 270)
			(layer "B.SilkS")
			(effects
				(font
					(size 0.7 0.7)
					(thickness 0.15)
				)
				(justify left bottom mirror)
			)
		)
		(property "Value" "C_22n_0402"
			(at -1.022927 -2.155213 270)
			(layer "B.Fab")
			(hide yes)
			(effects
				(font
					(size 0.7 0.7)
					(thickness 0.15)
				)
				(justify left bottom mirror)
			)
		)
		(property "Datasheet" "https://www.murata.com/products/productdetail?partno=GCM155R71H223MA55%23"
			(at 0 0 90)
			(layer "F.Fab")
			(hide yes)
			(effects
				(font
					(size 1.27 1.27)
					(thickness 0.15)
				)
			)
		)
		(property "Description" "SMD Multilayer Ceramic Capacitors, 0.022 µF, 50 V, 20%, 0402 [1005 Metric], X7R"
			(at 0 0 90)
			(layer "F.Fab")
			(hide yes)
			(effects
				(font
					(size 1.27 1.27)
					(thickness 0.15)
				)
			)
		)
		(property "Author" "Antmicro"
			(at 329.83 -64.25 0)
			(layer "B.Fab")
			(hide yes)
			(effects
				(font
					(size 1 1)
					(thickness 0.15)
				)
				(justify mirror)
			)
		)
		(property "Dielectric" ""
			(at 329.83 -64.25 0)
			(layer "B.Fab")
			(hide yes)
			(effects
				(font
					(size 1 1)
					(thickness 0.15)
				)
				(justify mirror)
			)
		)
		(property "License" "Apache-2.0"
			(at 329.83 -64.25 0)
			(layer "B.Fab")
			(hide yes)
			(effects
				(font
					(size 1 1)
					(thickness 0.15)
				)
				(justify mirror)
			)
		)
		(property "MPN" "GCM155R71H223MA55D"
			(at 329.83 -64.25 0)
			(layer "B.Fab")
			(hide yes)
			(effects
				(font
					(size 1 1)
					(thickness 0.15)
				)
				(justify mirror)
			)
		)
		(property "Manufacturer" "Murata"
			(at 329.83 -64.25 0)
			(layer "B.Fab")
			(hide yes)
			(effects
				(font
					(size 1 1)
					(thickness 0.15)
				)
				(justify mirror)
			)
		)
		(property "Public" ""
			(at 329.83 -64.25 0)
			(layer "B.Fab")
			(hide yes)
			(effects
				(font
					(size 1 1)
					(thickness 0.15)
				)
				(justify mirror)
			)
		)
		(property "Val" "22n"
			(at 329.83 -64.25 0)
			(layer "B.Fab")
			(hide yes)
			(effects
				(font
					(size 1 1)
					(thickness 0.15)
				)
				(justify mirror)
			)
		)
		(property "Voltage" ""
			(at 329.83 -64.25 0)
			(layer "B.Fab")
			(hide yes)
			(effects
				(font
					(size 1 1)
					(thickness 0.15)
				)
				(justify mirror)
			)
		)
		(sheetname "/FPGA Supply/")
		(sheetfile "fpga-supply.kicad_sch")
		(attr smd)
		(fp_rect
			(start -0.925 0.47)
			(end 0.925 -0.47)
			(stroke
				(width 0.05)
				(type default)
			)
			(fill no)
			(layer "B.CrtYd")
		)
		(fp_line
			(start 0.504 -0.248)
			(end -0.494 -0.248)
			(stroke
				(width 0.15)
				(type solid)
			)
			(layer "B.Fab")
		)
		(fp_line
			(start -0.494 -0.248)
			(end -0.494 0.25)
			(stroke
				(width 0.15)
				(type solid)
			)
			(layer "B.Fab")
		)
		(fp_line
			(start 0.504 0.25)
			(end 0.504 -0.248)
			(stroke
				(width 0.15)
				(type solid)
			)
			(layer "B.Fab")
		)
		(fp_line
			(start -0.494 0.25)
			(end 0.504 0.25)
			(stroke
				(width 0.15)
				(type solid)
			)
			(layer "B.Fab")
		)
		(fp_text user "License: Apache-2.0"
			(at -0.939 -5.799 270)
			(layer "B.Fab")
			(effects
				(font
					(size 0.7 0.7)
					(thickness 0.15)
				)
				(justify left bottom mirror)
			)
		)
		(fp_text user "Author: Antmicro"
			(at -0.939 -3.399 270)
			(layer "B.Fab")
			(effects
				(font
					(size 0.7 0.7)
					(thickness 0.15)
				)
				(justify left bottom mirror)
			)
		)
		(fp_text user "${REFERENCE}"
			(at -0.939 -4.599 270)
			(layer "B.Fab")
			(effects
				(font
					(size 0.7 0.7)
					(thickness 0.15)
				)
				(justify left bottom mirror)
			)
		)
		(pad "1" smd roundrect
			(at -0.48 0 90)
			(size 0.59 0.64)
			(layers "B.Cu" "B.Mask" "B.Paste")
			(roundrect_rratio 0.25)
			(net 417 "GND")
			(pintype "passive")
		)
		(pad "2" smd roundrect
			(at 0.48 0 90)
			(size 0.59 0.64)
			(layers "B.Cu" "B.Mask" "B.Paste")
			(roundrect_rratio 0.25)
			(net 47 "+1V05")
			(pintype "passive")
		)
	)
	(footprint "antmicro-footprints:C_0402_1005Metric"
		(layer "B.Cu")
		(at 191 142.811 -90)
		(descr "Capacitor SMD 0402")
		(tags "capacitor SMD 0402")
		(property "Reference" "C178"
			(at 2.239 -0.95 90)
			(layer "B.SilkS")
			(effects
				(font
					(size 0.7 0.7)
					(thickness 0.15)
				)
				(justify left bottom mirror)
			)
		)
		(property "Value" "C_100n_0402"
			(at -1.022927 -2.155213 90)
			(layer "B.Fab")
			(hide yes)
			(effects
				(font
					(size 0.7 0.7)
					(thickness 0.15)
				)
				(justify left bottom mirror)
			)
		)
		(property "Datasheet" "https://www.murata.com/products/productdetail?partno=GRM155R61H104KE14%23"
			(at 0 0 270)
			(layer "F.Fab")
			(hide yes)
			(effects
				(font
					(size 1.27 1.27)
					(thickness 0.15)
				)
			)
		)
		(property "Description" "SMD Multilayer Ceramic Capacitor, 0.1 µF, 50 V, 0402 [1005 Metric], ± 10%, X5R, GRM Series"
			(at 0 0 270)
			(layer "F.Fab")
			(hide yes)
			(effects
				(font
					(size 1.27 1.27)
					(thickness 0.15)
				)
			)
		)
		(property "Author" "Antmicro"
			(at 48.189 333.811 0)
			(layer "B.Fab")
			(hide yes)
			(effects
				(font
					(size 1 1)
					(thickness 0.15)
				)
				(justify mirror)
			)
		)
		(property "Dielectric" "X5R"
			(at 48.189 333.811 0)
			(layer "B.Fab")
			(hide yes)
			(effects
				(font
					(size 1 1)
					(thickness 0.15)
				)
				(justify mirror)
			)
		)
		(property "License" "Apache-2.0"
			(at 48.189 333.811 0)
			(layer "B.Fab")
			(hide yes)
			(effects
				(font
					(size 1 1)
					(thickness 0.15)
				)
				(justify mirror)
			)
		)
		(property "MPN" "GRM155R61H104KE14D"
			(at 48.189 333.811 0)
			(layer "B.Fab")
			(hide yes)
			(effects
				(font
					(size 1 1)
					(thickness 0.15)
				)
				(justify mirror)
			)
		)
		(property "Manufacturer" "Murata"
			(at 48.189 333.811 0)
			(layer "B.Fab")
			(hide yes)
			(effects
				(font
					(size 1 1)
					(thickness 0.15)
				)
				(justify mirror)
			)
		)
		(property "Public" ""
			(at 48.189 333.811 0)
			(layer "B.Fab")
			(hide yes)
			(effects
				(font
					(size 1 1)
					(thickness 0.15)
				)
				(justify mirror)
			)
		)
		(property "Val" "100n"
			(at 48.189 333.811 0)
			(layer "B.Fab")
			(hide yes)
			(effects
				(font
					(size 1 1)
					(thickness 0.15)
				)
				(justify mirror)
			)
		)
		(property "Voltage" "50V"
			(at 48.189 333.811 0)
			(layer "B.Fab")
			(hide yes)
			(effects
				(font
					(size 1 1)
					(thickness 0.15)
				)
				(justify mirror)
			)
		)
		(sheetname "/FPGA GPIO/")
		(sheetfile "fpga-gpio.kicad_sch")
		(attr smd)
		(fp_rect
			(start -0.925 0.47)
			(end 0.925 -0.47)
			(stroke
				(width 0.05)
				(type default)
			)
			(fill no)
			(layer "B.CrtYd")
		)
		(fp_line
			(start -0.494 0.25)
			(end 0.504 0.25)
			(stroke
				(width 0.15)
				(type solid)
			)
			(layer "B.Fab")
		)
		(fp_line
			(start 0.504 0.25)
			(end 0.504 -0.248)
			(stroke
				(width 0.15)
				(type solid)
			)
			(layer "B.Fab")
		)
		(fp_line
			(start -0.494 -0.248)
			(end -0.494 0.25)
			(stroke
				(width 0.15)
				(type solid)
			)
			(layer "B.Fab")
		)
		(fp_line
			(start 0.504 -0.248)
			(end -0.494 -0.248)
			(stroke
				(width 0.15)
				(type solid)
			)
			(layer "B.Fab")
		)
		(fp_text user "License: Apache-2.0"
			(at -0.939 -5.799 90)
			(layer "B.Fab")
			(effects
				(font
					(size 0.7 0.7)
					(thickness 0.15)
				)
				(justify left bottom mirror)
			)
		)
		(fp_text user "${REFERENCE}"
			(at -0.939 -4.599 90)
			(layer "B.Fab")
			(effects
				(font
					(size 0.7 0.7)
					(thickness 0.15)
				)
				(justify left bottom mirror)
			)
		)
		(fp_text user "Author: Antmicro"
			(at -0.939 -3.399 90)
			(layer "B.Fab")
			(effects
				(font
					(size 0.7 0.7)
					(thickness 0.15)
				)
				(justify left bottom mirror)
			)
		)
		(pad "1" smd roundrect
			(at -0.48 0 270)
			(size 0.59 0.64)
			(layers "B.Cu" "B.Mask" "B.Paste")
			(roundrect_rratio 0.25)
			(net 649 "VDD")
			(pintype "passive")
		)
		(pad "2" smd roundrect
			(at 0.48 0 270)
			(size 0.59 0.64)
			(layers "B.Cu" "B.Mask" "B.Paste")
			(roundrect_rratio 0.25)
			(net 417 "GND")
			(pintype "passive")
		)
	)
	(footprint "antmicro-footprints:R_0402_1005Metric"
		(layer "B.Cu")
		(at 222.35 133.755 90)
		(descr "Resistor SMD 0402")
		(tags "resistor SMD 0402")
		(property "Reference" "R3"
			(at 0.28 1.3 270)
			(layer "B.SilkS")
			(effects
				(font
					(size 0.7 0.7)
					(thickness 0.15)
				)
				(justify left bottom mirror)
			)
		)
		(property "Value" "R_20k_0402"
			(at -1.011843 -1.772047 270)
			(layer "B.Fab")
			(hide yes)
			(effects
				(font
					(size 0.7 0.7)
					(thickness 0.15)
				)
				(justify left bottom mirror)
			)
		)
		(property "Datasheet" "https://www.bourns.com/docs/product-datasheets/cr.pdf"
			(at 0 0 90)
			(layer "F.Fab")
			(hide yes)
			(effects
				(font
					(size 1.27 1.27)
					(thickness 0.15)
				)
			)
		)
		(property "Description" "SMD Chip Resistor, 20 kohm, ± 1%, 62.5 mW, 0402 [1005 Metric], Thick Film, General Purpose"
			(at 0 0 90)
			(layer "F.Fab")
			(hide yes)
			(effects
				(font
					(size 1.27 1.27)
					(thickness 0.15)
				)
			)
		)
		(property "Author" "Antmicro"
			(at 356.105 -88.595 0)
			(layer "B.Fab")
			(hide yes)
			(effects
				(font
					(size 1 1)
					(thickness 0.15)
				)
				(justify mirror)
			)
		)
		(property "License" "Apache-2.0"
			(at 356.105 -88.595 0)
			(layer "B.Fab")
			(hide yes)
			(effects
				(font
					(size 1 1)
					(thickness 0.15)
				)
				(justify mirror)
			)
		)
		(property "MPN" "CR0402-FX-2002GLF"
			(at 356.105 -88.595 0)
			(layer "B.Fab")
			(hide yes)
			(effects
				(font
					(size 1 1)
					(thickness 0.15)
				)
				(justify mirror)
			)
		)
		(property "Manufacturer" "Bourns"
			(at 356.105 -88.595 0)
			(layer "B.Fab")
			(hide yes)
			(effects
				(font
					(size 1 1)
					(thickness 0.15)
				)
				(justify mirror)
			)
		)
		(property "Public" ""
			(at 356.105 -88.595 0)
			(layer "B.Fab")
			(hide yes)
			(effects
				(font
					(size 1 1)
					(thickness 0.15)
				)
				(justify mirror)
			)
		)
		(property "Tolerance" "1%"
			(at 356.105 -88.595 0)
			(layer "B.Fab")
			(hide yes)
			(effects
				(font
					(size 1 1)
					(thickness 0.15)
				)
				(justify mirror)
			)
		)
		(property "Val" "20k"
			(at 356.105 -88.595 0)
			(layer "B.Fab")
			(hide yes)
			(effects
				(font
					(size 1 1)
					(thickness 0.15)
				)
				(justify mirror)
			)
		)
		(sheetname "/Supply/")
		(sheetfile "supply.kicad_sch")
		(attr smd)
		(fp_rect
			(start -0.925 0.47)
			(end 0.925 -0.47)
			(stroke
				(width 0.05)
				(type default)
			)
			(fill no)
			(layer "B.CrtYd")
		)
		(fp_rect
			(start -0.5 0.25)
			(end 0.5 -0.25)
			(stroke
				(width 0.15)
				(type solid)
			)
			(fill no)
			(layer "B.Fab")
		)
		(fp_text user "License: Apache-2.0"
			(at -0.95 -5.169 270)
			(layer "B.Fab")
			(effects
				(font
					(size 0.7 0.7)
					(thickness 0.15)
				)
				(justify left bottom mirror)
			)
		)
		(fp_text user "Author: Antmicro"
			(at -0.95 -4.169 270)
			(layer "B.Fab")
			(effects
				(font
					(size 0.7 0.7)
					(thickness 0.15)
				)
				(justify left bottom mirror)
			)
		)
		(fp_text user "${REFERENCE}"
			(at -0.95 -3.168 270)
			(layer "B.Fab")
			(effects
				(font
					(size 0.7 0.7)
					(thickness 0.15)
				)
				(justify left bottom mirror)
			)
		)
		(pad "1" smd roundrect
			(at -0.48 0 90)
			(size 0.59 0.64)
			(layers "B.Cu" "B.Mask" "B.Paste")
			(roundrect_rratio 0.25)
			(net 417 "GND")
			(pintype "passive")
		)
		(pad "2" smd roundrect
			(at 0.48 0 90)
			(size 0.59 0.64)
			(layers "B.Cu" "B.Mask" "B.Paste")
			(roundrect_rratio 0.25)
			(net 186 "/Supply/PR")
			(pintype "passive")
		)
	)
	(footprint "antmicro-footprints:R_0402_1005Metric"
		(layer "B.Cu")
		(at 211.175 152.55 -90)
		(descr "Resistor SMD 0402")
		(tags "resistor SMD 0402")
		(property "Reference" "R77"
			(at 0.8 -0.425 90)
			(layer "B.SilkS")
			(effects
				(font
					(size 0.7 0.7)
					(thickness 0.15)
				)
				(justify left bottom mirror)
			)
		)
		(property "Value" "R_10k_0402"
			(at -1.011843 -1.772047 90)
			(layer "B.Fab")
			(hide yes)
			(effects
				(font
					(size 0.7 0.7)
					(thickness 0.15)
				)
				(justify left bottom mirror)
			)
		)
		(property "Datasheet" "https://www.bourns.com/docs/product-datasheets/cr.pdf"
			(at 0 0 270)
			(layer "F.Fab")
			(hide yes)
			(effects
				(font
					(size 1.27 1.27)
					(thickness 0.15)
				)
			)
		)
		(property "Description" "SMD Chip Resistor, 10 kohm, ± 1%, 62.5 mW, 0402 [1005 Metric], Thick Film, General Purpose"
			(at 0 0 270)
			(layer "F.Fab")
			(hide yes)
			(effects
				(font
					(size 1.27 1.27)
					(thickness 0.15)
				)
			)
		)
		(property "Author" "Antmicro"
			(at 58.625 363.725 0)
			(layer "B.Fab")
			(hide yes)
			(effects
				(font
					(size 1 1)
					(thickness 0.15)
				)
				(justify mirror)
			)
		)
		(property "License" "Apache-2.0"
			(at 58.625 363.725 0)
			(layer "B.Fab")
			(hide yes)
			(effects
				(font
					(size 1 1)
					(thickness 0.15)
				)
				(justify mirror)
			)
		)
		(property "MPN" "CR0402-FX-1002GLF"
			(at 58.625 363.725 0)
			(layer "B.Fab")
			(hide yes)
			(effects
				(font
					(size 1 1)
					(thickness 0.15)
				)
				(justify mirror)
			)
		)
		(property "Manufacturer" "Bourns"
			(at 58.625 363.725 0)
			(layer "B.Fab")
			(hide yes)
			(effects
				(font
					(size 1 1)
					(thickness 0.15)
				)
				(justify mirror)
			)
		)
		(property "Public" ""
			(at 58.625 363.725 0)
			(layer "B.Fab")
			(hide yes)
			(effects
				(font
					(size 1 1)
					(thickness 0.15)
				)
				(justify mirror)
			)
		)
		(property "Tolerance" "1%"
			(at 58.625 363.725 0)
			(layer "B.Fab")
			(hide yes)
			(effects
				(font
					(size 1 1)
					(thickness 0.15)
				)
				(justify mirror)
			)
		)
		(property "Val" "10k"
			(at 58.625 363.725 0)
			(layer "B.Fab")
			(hide yes)
			(effects
				(font
					(size 1 1)
					(thickness 0.15)
				)
				(justify mirror)
			)
		)
		(sheetname "/USB/")
		(sheetfile "usb.kicad_sch")
		(attr smd)
		(fp_rect
			(start -0.925 0.47)
			(end 0.925 -0.47)
			(stroke
				(width 0.05)
				(type default)
			)
			(fill no)
			(layer "B.CrtYd")
		)
		(fp_rect
			(start -0.5 0.25)
			(end 0.5 -0.25)
			(stroke
				(width 0.15)
				(type solid)
			)
			(fill no)
			(layer "B.Fab")
		)
		(fp_text user "Author: Antmicro"
			(at -0.95 -4.169 90)
			(layer "B.Fab")
			(effects
				(font
					(size 0.7 0.7)
					(thickness 0.15)
				)
				(justify left bottom mirror)
			)
		)
		(fp_text user "${REFERENCE}"
			(at -0.95 -3.168 90)
			(layer "B.Fab")
			(effects
				(font
					(size 0.7 0.7)
					(thickness 0.15)
				)
				(justify left bottom mirror)
			)
		)
		(fp_text user "License: Apache-2.0"
			(at -0.95 -5.169 90)
			(layer "B.Fab")
			(effects
				(font
					(size 0.7 0.7)
					(thickness 0.15)
				)
				(justify left bottom mirror)
			)
		)
		(pad "1" smd roundrect
			(at -0.48 0 270)
			(size 0.59 0.64)
			(layers "B.Cu" "B.Mask" "B.Paste")
			(roundrect_rratio 0.25)
			(net 62 "USB_OTG_ID")
			(pintype "passive")
		)
		(pad "2" smd roundrect
			(at 0.48 0 270)
			(size 0.59 0.64)
			(layers "B.Cu" "B.Mask" "B.Paste")
			(roundrect_rratio 0.25)
			(net 50 "+3V3")
			(pintype "passive")
		)
	)
)
